G04*
G04 #@! TF.GenerationSoftware,Altium Limited,Altium Designer,23.6.0 (18)*
G04*
G04 Layer_Color=128*
%FSLAX44Y44*%
%MOMM*%
G71*
G04*
G04 #@! TF.SameCoordinates,0D6CC9A4-690D-4EF8-AA6E-9FB67146BD04*
G04*
G04*
G04 #@! TF.FilePolarity,Positive*
G04*
G01*
G75*
%ADD25R,0.6200X0.5700*%
%ADD31R,0.9500X1.0000*%
%ADD32R,1.0000X0.9500*%
%ADD33R,0.6200X0.6000*%
%ADD35R,0.6000X0.6200*%
%ADD82R,1.5000X0.4500*%
%ADD83R,1.5500X0.6000*%
%ADD84R,0.8500X0.3000*%
%ADD85R,1.6000X1.6000*%
%ADD86R,1.1000X0.3000*%
%ADD87R,0.8000X1.0000*%
%ADD88R,0.6000X0.5500*%
%ADD89C,6.2000*%
%ADD90R,0.5500X0.6000*%
D25*
X99000Y226250D02*
D03*
Y216650D02*
D03*
D31*
X374500Y389088D02*
D03*
X390500D02*
D03*
X331500Y412500D02*
D03*
X315500D02*
D03*
D32*
X200650Y174955D02*
D03*
Y190955D02*
D03*
X220624Y328550D02*
D03*
Y312550D02*
D03*
D33*
X193167D02*
D03*
Y321750D02*
D03*
X206778D02*
D03*
Y312550D02*
D03*
X184407Y191350D02*
D03*
Y182150D02*
D03*
X171518Y182500D02*
D03*
Y191700D02*
D03*
D35*
X113425Y358378D02*
D03*
X122625D02*
D03*
X306100Y349750D02*
D03*
X296900D02*
D03*
D82*
X64618Y390689D02*
D03*
X122618D02*
D03*
Y377689D02*
D03*
X64618Y371189D02*
D03*
Y377689D02*
D03*
Y384189D02*
D03*
X122618D02*
D03*
Y371189D02*
D03*
D83*
X171500Y215250D02*
D03*
Y240650D02*
D03*
X117500D02*
D03*
Y227950D02*
D03*
Y215250D02*
D03*
X171500Y227950D02*
D03*
Y253350D02*
D03*
X117500D02*
D03*
X171250Y274450D02*
D03*
X117250D02*
D03*
Y299850D02*
D03*
X171250Y312550D02*
D03*
Y299850D02*
D03*
Y287150D02*
D03*
X117250D02*
D03*
Y312550D02*
D03*
D84*
X276914Y360775D02*
D03*
Y365775D02*
D03*
Y370775D02*
D03*
Y375775D02*
D03*
X305914Y370775D02*
D03*
Y375775D02*
D03*
Y365775D02*
D03*
Y360775D02*
D03*
D85*
X291414Y368275D02*
D03*
D86*
X71500Y266500D02*
D03*
Y261500D02*
D03*
Y256500D02*
D03*
Y251500D02*
D03*
Y231500D02*
D03*
Y236500D02*
D03*
Y241500D02*
D03*
Y246500D02*
D03*
Y276500D02*
D03*
Y271500D02*
D03*
X36500D02*
D03*
Y276500D02*
D03*
Y246500D02*
D03*
Y241500D02*
D03*
Y236500D02*
D03*
Y231500D02*
D03*
Y251500D02*
D03*
Y256500D02*
D03*
Y261500D02*
D03*
Y266500D02*
D03*
D87*
X279500Y339500D02*
D03*
X264500D02*
D03*
X122500Y343710D02*
D03*
X107500D02*
D03*
D88*
X421000Y193594D02*
D03*
X412500D02*
D03*
X279005Y198941D02*
D03*
X270505D02*
D03*
X224129Y199191D02*
D03*
X232629D02*
D03*
X27250Y357460D02*
D03*
X35750D02*
D03*
X27250Y367710D02*
D03*
X35750D02*
D03*
X27285Y397960D02*
D03*
X35785D02*
D03*
X35750Y347460D02*
D03*
X27250D02*
D03*
X35750Y377710D02*
D03*
X27250D02*
D03*
X35750Y387710D02*
D03*
X27250D02*
D03*
X334750Y343750D02*
D03*
X326250D02*
D03*
X334750Y354236D02*
D03*
X326250D02*
D03*
Y334250D02*
D03*
X334750D02*
D03*
X326000Y363750D02*
D03*
X334500D02*
D03*
X394750Y274431D02*
D03*
X386250D02*
D03*
D89*
X95000Y71000D02*
D03*
X406000Y41000D02*
D03*
X413000Y452000D02*
D03*
X95000Y437000D02*
D03*
D90*
X243755Y190711D02*
D03*
Y199211D02*
D03*
X258755Y190441D02*
D03*
Y198941D02*
D03*
X338500Y382750D02*
D03*
Y374250D02*
D03*
X327500Y374500D02*
D03*
Y383000D02*
D03*
X394750Y284000D02*
D03*
Y292500D02*
D03*
X403000Y202094D02*
D03*
Y193594D02*
D03*
M02*
